(kicad_pcb
	(version 20260206)
	(generator "pcbnew")
	(generator_version "10.0")
	(general
		(thickness 1.6)
		(legacy_teardrops no)
	)
	(paper "A4")
	(title_block
		(title "01162023_DA0F0TEBIF0_F0T_Expander_BD_F_brd_V02_OCP.brd")
		(comment 1 "Grand Teton / footprints 4750-4756 of 9728")
	)
	(layers
		(0 "F.Cu" signal "TOP")
		(4 "In1.Cu" signal "GND")
		(6 "In2.Cu" signal "VCC")
		(8 "In3.Cu" signal "VCC1")
		(10 "In4.Cu" signal "GND1")
		(12 "In5.Cu" signal "IN1")
		(14 "In6.Cu" signal "GND2")
		(16 "In7.Cu" signal "IN2")
		(18 "In8.Cu" signal "GND3")
		(20 "In9.Cu" signal "IN3")
		(22 "In10.Cu" signal "GND4")
		(24 "In11.Cu" signal "IN4")
		(26 "In12.Cu" signal "GND5")
		(28 "In13.Cu" signal "IN5")
		(30 "In14.Cu" signal "GND6")
		(32 "In15.Cu" signal "IN6")
		(34 "In16.Cu" signal "GND7")
		(2 "B.Cu" signal "BOTTOM")
		(9 "F.Adhes" user "F.Adhesive")
		(11 "B.Adhes" user "B.Adhesive")
		(13 "F.Paste" user "Package Geometry/Pastemask Top")
		(15 "B.Paste" user "Package Geometry/Pastemask Bottom")
		(5 "F.SilkS" user "Ref Des/Silkscreen Top")
		(7 "B.SilkS" user "Ref Des/Silkscreen Bottom")
		(1 "F.Mask" user "Board Geometry/Soldermask Top")
		(3 "B.Mask" user "Board Geometry/Soldermask Bottom")
		(17 "Dwgs.User" user "User.Drawings")
		(19 "Cmts.User" user "User.Comments")
		(21 "Eco1.User" user "User.Eco1")
		(23 "Eco2.User" user "User.Eco2")
		(25 "Edge.Cuts" user "Board Geometry/Outline")
		(27 "Margin" user)
		(31 "F.CrtYd" user "Package Geometry/Place Bound Top")
		(29 "B.CrtYd" user "Package Geometry/Place Bound Bottom")
		(35 "F.Fab" user "Ref Des/Assembly Top")
		(33 "B.Fab" user "Ref Des/Assembly Bottom")
	)
	(footprint ""
		(layer "F.Cu")
		(at 284.226 -86.106 180)
		(property "Reference" "R484"
			(at 0 0 180)
			(layer "F.SilkS")
			(hide yes)
			(effects
				(font
					(size 1.27 1.27)
				)
			)
		)
		(property "Value" ""
			(at 0 0 180)
			(layer "F.Fab")
			(effects
				(font
					(size 1.27 1.27)
				)
			)
		)
		(duplicate_pad_numbers_are_jumpers no)
		(fp_line
			(start 0.7874 0.4064)
			(end -0.7874 0.4064)
			(stroke
				(width 0.1524)
				(type default)
			)
			(layer "F.SilkS")
		)
		(fp_line
			(start 0.7874 -0.4064)
			(end 0.7874 0.4064)
			(stroke
				(width 0.1524)
				(type default)
			)
			(layer "F.SilkS")
		)
		(fp_line
			(start -0.7874 0.4064)
			(end -0.7874 -0.4064)
			(stroke
				(width 0.1524)
				(type default)
			)
			(layer "F.SilkS")
		)
		(fp_line
			(start -0.7874 -0.4064)
			(end 0.7874 -0.4064)
			(stroke
				(width 0.1524)
				(type default)
			)
			(layer "F.SilkS")
		)
		(fp_line
			(start 0.67945 0.3048)
			(end 0.120396 0.3048)
			(stroke
				(width 0.1)
				(type default)
			)
			(layer "F.Fab")
		)
		(fp_line
			(start 0.67945 -0.3048)
			(end 0.67945 0.3048)
			(stroke
				(width 0.1)
				(type default)
			)
			(layer "F.Fab")
		)
		(fp_line
			(start 0.12065 -0.2794)
			(end 0.12065 -0.3048)
			(stroke
				(width 0.1)
				(type default)
			)
			(layer "F.Fab")
		)
		(fp_line
			(start 0.12065 -0.3048)
			(end 0.67945 -0.3048)
			(stroke
				(width 0.1)
				(type default)
			)
			(layer "F.Fab")
		)
		(fp_line
			(start 0.120396 0.3048)
			(end 0.120396 0.2794)
			(stroke
				(width 0.1)
				(type default)
			)
			(layer "F.Fab")
		)
		(fp_line
			(start 0.120396 0.2794)
			(end -0.12065 0.2794)
			(stroke
				(width 0.1)
				(type default)
			)
			(layer "F.Fab")
		)
		(fp_line
			(start -0.12065 0.3048)
			(end -0.67945 0.3048)
			(stroke
				(width 0.1)
				(type default)
			)
			(layer "F.Fab")
		)
		(fp_line
			(start -0.12065 0.2794)
			(end -0.12065 0.3048)
			(stroke
				(width 0.1)
				(type default)
			)
			(layer "F.Fab")
		)
		(fp_line
			(start -0.12065 -0.2794)
			(end 0.12065 -0.2794)
			(stroke
				(width 0.1)
				(type default)
			)
			(layer "F.Fab")
		)
		(fp_line
			(start -0.12065 -0.305054)
			(end -0.12065 -0.2794)
			(stroke
				(width 0.1)
				(type default)
			)
			(layer "F.Fab")
		)
		(fp_line
			(start -0.67945 0.3048)
			(end -0.67945 -0.305054)
			(stroke
				(width 0.1)
				(type default)
			)
			(layer "F.Fab")
		)
		(fp_line
			(start -0.67945 -0.305054)
			(end -0.12065 -0.305054)
			(stroke
				(width 0.1)
				(type default)
			)
			(layer "F.Fab")
		)
		(pad "1" smd circle
			(at -0.40005 0 180)
			(size 0 0)
			(layers "F.Cu" "F.Mask" "F.Paste")
			(net "BB_FRU_A0")
		)
		(pad "2" smd circle
			(at 0.40005 0 180)
			(size 0 0)
			(layers "F.Cu" "F.Mask" "F.Paste")
			(net "P3V3_AUX")
		)
	)
	(footprint ""
		(layer "F.Cu")
		(at 134.794244 -213.5378 180)
		(property "Reference" "R6644"
			(at 0 0 180)
			(layer "F.SilkS")
			(hide yes)
			(effects
				(font
					(size 1.27 1.27)
				)
			)
		)
		(property "Value" ""
			(at 0 0 180)
			(layer "F.Fab")
			(effects
				(font
					(size 1.27 1.27)
				)
			)
		)
		(duplicate_pad_numbers_are_jumpers no)
		(fp_line
			(start 0.7874 0.4064)
			(end -0.7874 0.4064)
			(stroke
				(width 0.1524)
				(type default)
			)
			(layer "F.SilkS")
		)
		(fp_line
			(start 0.7874 -0.4064)
			(end 0.7874 0.4064)
			(stroke
				(width 0.1524)
				(type default)
			)
			(layer "F.SilkS")
		)
		(fp_line
			(start -0.7874 0.4064)
			(end -0.7874 -0.4064)
			(stroke
				(width 0.1524)
				(type default)
			)
			(layer "F.SilkS")
		)
		(fp_line
			(start -0.7874 -0.4064)
			(end 0.7874 -0.4064)
			(stroke
				(width 0.1524)
				(type default)
			)
			(layer "F.SilkS")
		)
		(fp_line
			(start 0.67945 0.3048)
			(end 0.120396 0.3048)
			(stroke
				(width 0.1)
				(type default)
			)
			(layer "F.Fab")
		)
		(fp_line
			(start 0.67945 -0.3048)
			(end 0.67945 0.3048)
			(stroke
				(width 0.1)
				(type default)
			)
			(layer "F.Fab")
		)
		(fp_line
			(start 0.12065 -0.2794)
			(end 0.12065 -0.3048)
			(stroke
				(width 0.1)
				(type default)
			)
			(layer "F.Fab")
		)
		(fp_line
			(start 0.12065 -0.3048)
			(end 0.67945 -0.3048)
			(stroke
				(width 0.1)
				(type default)
			)
			(layer "F.Fab")
		)
		(fp_line
			(start 0.120396 0.3048)
			(end 0.120396 0.2794)
			(stroke
				(width 0.1)
				(type default)
			)
			(layer "F.Fab")
		)
		(fp_line
			(start 0.120396 0.2794)
			(end -0.12065 0.2794)
			(stroke
				(width 0.1)
				(type default)
			)
			(layer "F.Fab")
		)
		(fp_line
			(start -0.12065 0.3048)
			(end -0.67945 0.3048)
			(stroke
				(width 0.1)
				(type default)
			)
			(layer "F.Fab")
		)
		(fp_line
			(start -0.12065 0.2794)
			(end -0.12065 0.3048)
			(stroke
				(width 0.1)
				(type default)
			)
			(layer "F.Fab")
		)
		(fp_line
			(start -0.12065 -0.2794)
			(end 0.12065 -0.2794)
			(stroke
				(width 0.1)
				(type default)
			)
			(layer "F.Fab")
		)
		(fp_line
			(start -0.12065 -0.305054)
			(end -0.12065 -0.2794)
			(stroke
				(width 0.1)
				(type default)
			)
			(layer "F.Fab")
		)
		(fp_line
			(start -0.67945 0.3048)
			(end -0.67945 -0.305054)
			(stroke
				(width 0.1)
				(type default)
			)
			(layer "F.Fab")
		)
		(fp_line
			(start -0.67945 -0.305054)
			(end -0.12065 -0.305054)
			(stroke
				(width 0.1)
				(type default)
			)
			(layer "F.Fab")
		)
		(pad "1" smd circle
			(at -0.40005 0 180)
			(size 0 0)
			(layers "F.Cu" "F.Mask" "F.Paste")
			(net "UART_PEX3_CLI_RX")
		)
		(pad "2" smd circle
			(at 0.40005 0 180)
			(size 0 0)
			(layers "F.Cu" "F.Mask" "F.Paste")
			(net "UART_PEX3_CLI_R_RX")
		)
	)
	(footprint ""
		(layer "F.Cu")
		(at 271.480534 -107.403138)
		(property "Reference" "C478"
			(at 0 0 0)
			(layer "F.SilkS")
			(hide yes)
			(effects
				(font
					(size 1.27 1.27)
				)
			)
		)
		(property "Value" ""
			(at 0 0 0)
			(layer "F.Fab")
			(effects
				(font
					(size 1.27 1.27)
				)
			)
		)
		(duplicate_pad_numbers_are_jumpers no)
		(fp_line
			(start -0.299974 -0.150114)
			(end 0.299974 -0.150114)
			(stroke
				(width 0.1)
				(type default)
			)
			(layer "F.Fab")
		)
		(fp_line
			(start -0.299974 0.150114)
			(end -0.299974 -0.150114)
			(stroke
				(width 0.1)
				(type default)
			)
			(layer "F.Fab")
		)
		(fp_line
			(start 0.299974 -0.150114)
			(end 0.299974 0.150114)
			(stroke
				(width 0.1)
				(type default)
			)
			(layer "F.Fab")
		)
		(fp_line
			(start 0.299974 0.150114)
			(end -0.299974 0.150114)
			(stroke
				(width 0.1)
				(type default)
			)
			(layer "F.Fab")
		)
		(pad "1" smd rect
			(at -0.2667 0)
			(size 0.3048 0.381)
			(layers "F.Cu" "F.Mask" "F.Paste")
			(net "P5E_PEX2_STN1_TX_DN<20>")
		)
		(pad "2" smd rect
			(at 0.2667 0)
			(size 0.3048 0.381)
			(layers "F.Cu" "F.Mask" "F.Paste")
			(net "P5E_PEX2_STN1_TX_C_DN<20>")
		)
	)
	(footprint ""
		(layer "F.Cu")
		(at 87.194898 -59.577986 90)
		(property "Reference" "PC543"
			(at 0 0 90)
			(layer "F.SilkS")
			(hide yes)
			(effects
				(font
					(size 1.27 1.27)
				)
			)
		)
		(property "Value" ""
			(at 0 0 90)
			(layer "F.Fab")
			(effects
				(font
					(size 1.27 1.27)
				)
			)
		)
		(duplicate_pad_numbers_are_jumpers no)
		(fp_line
			(start 0.7874 -0.4064)
			(end 0.7874 0.4064)
			(stroke
				(width 0.1524)
				(type default)
			)
			(layer "F.SilkS")
		)
		(fp_line
			(start -0.7874 -0.4064)
			(end 0.7874 -0.4064)
			(stroke
				(width 0.1524)
				(type default)
			)
			(layer "F.SilkS")
		)
		(fp_line
			(start 0.7874 0.4064)
			(end -0.7874 0.4064)
			(stroke
				(width 0.1524)
				(type default)
			)
			(layer "F.SilkS")
		)
		(fp_line
			(start -0.7874 0.4064)
			(end -0.7874 -0.4064)
			(stroke
				(width 0.1524)
				(type default)
			)
			(layer "F.SilkS")
		)
		(fp_line
			(start -0.12065 -0.305054)
			(end -0.12065 -0.2794)
			(stroke
				(width 0.1)
				(type default)
			)
			(layer "F.Fab")
		)
		(fp_line
			(start -0.67945 -0.305054)
			(end -0.12065 -0.305054)
			(stroke
				(width 0.1)
				(type default)
			)
			(layer "F.Fab")
		)
		(fp_line
			(start 0.67945 -0.3048)
			(end 0.67945 0.3048)
			(stroke
				(width 0.1)
				(type default)
			)
			(layer "F.Fab")
		)
		(fp_line
			(start 0.12065 -0.3048)
			(end 0.67945 -0.3048)
			(stroke
				(width 0.1)
				(type default)
			)
			(layer "F.Fab")
		)
		(fp_line
			(start 0.12065 -0.2794)
			(end 0.12065 -0.3048)
			(stroke
				(width 0.1)
				(type default)
			)
			(layer "F.Fab")
		)
		(fp_line
			(start -0.12065 -0.2794)
			(end 0.12065 -0.2794)
			(stroke
				(width 0.1)
				(type default)
			)
			(layer "F.Fab")
		)
		(fp_line
			(start 0.120396 0.2794)
			(end -0.12065 0.2794)
			(stroke
				(width 0.1)
				(type default)
			)
			(layer "F.Fab")
		)
		(fp_line
			(start -0.12065 0.2794)
			(end -0.12065 0.3048)
			(stroke
				(width 0.1)
				(type default)
			)
			(layer "F.Fab")
		)
		(fp_line
			(start 0.67945 0.3048)
			(end 0.120396 0.3048)
			(stroke
				(width 0.1)
				(type default)
			)
			(layer "F.Fab")
		)
		(fp_line
			(start 0.120396 0.3048)
			(end 0.120396 0.2794)
			(stroke
				(width 0.1)
				(type default)
			)
			(layer "F.Fab")
		)
		(fp_line
			(start -0.12065 0.3048)
			(end -0.67945 0.3048)
			(stroke
				(width 0.1)
				(type default)
			)
			(layer "F.Fab")
		)
		(fp_line
			(start -0.67945 0.3048)
			(end -0.67945 -0.305054)
			(stroke
				(width 0.1)
				(type default)
			)
			(layer "F.Fab")
		)
		(pad "1" smd circle
			(at -0.40005 0 90)
			(size 0 0)
			(layers "F.Cu" "F.Mask" "F.Paste")
			(net "P3V3_SSD3_SS")
		)
		(pad "2" smd circle
			(at 0.40005 0 90)
			(size 0 0)
			(layers "F.Cu" "F.Mask" "F.Paste")
			(net "GND")
		)
	)
	(footprint ""
		(layer "F.Cu")
		(at 52.267866 -53.051456)
		(property "Reference" "R4460"
			(at 0 0 0)
			(layer "F.SilkS")
			(hide yes)
			(effects
				(font
					(size 1.27 1.27)
				)
			)
		)
		(property "Value" ""
			(at 0 0 0)
			(layer "F.Fab")
			(effects
				(font
					(size 1.27 1.27)
				)
			)
		)
		(duplicate_pad_numbers_are_jumpers no)
		(fp_line
			(start -0.7874 -0.4064)
			(end 0.7874 -0.4064)
			(stroke
				(width 0.1524)
				(type default)
			)
			(layer "F.SilkS")
		)
		(fp_line
			(start -0.7874 0.4064)
			(end -0.7874 -0.4064)
			(stroke
				(width 0.1524)
				(type default)
			)
			(layer "F.SilkS")
		)
		(fp_line
			(start 0.7874 -0.4064)
			(end 0.7874 0.4064)
			(stroke
				(width 0.1524)
				(type default)
			)
			(layer "F.SilkS")
		)
		(fp_line
			(start 0.7874 0.4064)
			(end -0.7874 0.4064)
			(stroke
				(width 0.1524)
				(type default)
			)
			(layer "F.SilkS")
		)
		(fp_line
			(start -0.67945 -0.305054)
			(end -0.12065 -0.305054)
			(stroke
				(width 0.1)
				(type default)
			)
			(layer "F.Fab")
		)
		(fp_line
			(start -0.67945 0.3048)
			(end -0.67945 -0.305054)
			(stroke
				(width 0.1)
				(type default)
			)
			(layer "F.Fab")
		)
		(fp_line
			(start -0.12065 -0.305054)
			(end -0.12065 -0.2794)
			(stroke
				(width 0.1)
				(type default)
			)
			(layer "F.Fab")
		)
		(fp_line
			(start -0.12065 -0.2794)
			(end 0.12065 -0.2794)
			(stroke
				(width 0.1)
				(type default)
			)
			(layer "F.Fab")
		)
		(fp_line
			(start -0.12065 0.2794)
			(end -0.12065 0.3048)
			(stroke
				(width 0.1)
				(type default)
			)
			(layer "F.Fab")
		)
		(fp_line
			(start -0.12065 0.3048)
			(end -0.67945 0.3048)
			(stroke
				(width 0.1)
				(type default)
			)
			(layer "F.Fab")
		)
		(fp_line
			(start 0.120396 0.2794)
			(end -0.12065 0.2794)
			(stroke
				(width 0.1)
				(type default)
			)
			(layer "F.Fab")
		)
		(fp_line
			(start 0.120396 0.3048)
			(end 0.120396 0.2794)
			(stroke
				(width 0.1)
				(type default)
			)
			(layer "F.Fab")
		)
		(fp_line
			(start 0.12065 -0.3048)
			(end 0.67945 -0.3048)
			(stroke
				(width 0.1)
				(type default)
			)
			(layer "F.Fab")
		)
		(fp_line
			(start 0.12065 -0.2794)
			(end 0.12065 -0.3048)
			(stroke
				(width 0.1)
				(type default)
			)
			(layer "F.Fab")
		)
		(fp_line
			(start 0.67945 -0.3048)
			(end 0.67945 0.3048)
			(stroke
				(width 0.1)
				(type default)
			)
			(layer "F.Fab")
		)
		(fp_line
			(start 0.67945 0.3048)
			(end 0.120396 0.3048)
			(stroke
				(width 0.1)
				(type default)
			)
			(layer "F.Fab")
		)
		(pad "1" smd circle
			(at -0.40005 0)
			(size 0 0)
			(layers "F.Cu" "F.Mask" "F.Paste")
			(net "PWRGD_P12V_SSD1")
		)
		(pad "2" smd circle
			(at 0.40005 0)
			(size 0 0)
			(layers "F.Cu" "F.Mask" "F.Paste")
			(net "PWRGD_P12V_SSD1_R")
		)
	)
	(footprint ""
		(layer "F.Cu")
		(at 23.502112 -254.850646 180)
		(property "Reference" "D1"
			(at 1.109726 -1.44526 0)
			(unlocked yes)
			(layer "F.SilkS")
			(effects
				(font
					(size 0.7874 0.5842)
					(thickness 0.1524)
				)
				(justify left)
			)
		)
		(property "Value" ""
			(at 0 0 180)
			(layer "F.Fab")
			(effects
				(font
					(size 1.27 1.27)
				)
			)
		)
		(duplicate_pad_numbers_are_jumpers no)
		(fp_line
			(start 1.16078 0.4826)
			(end -0.64008 0.4826)
			(stroke
				(width 0.1524)
				(type default)
			)
			(layer "F.SilkS")
		)
		(fp_line
			(start 1.16078 -0.4826)
			(end 1.16078 0.4826)
			(stroke
				(width 0.1524)
				(type default)
			)
			(layer "F.SilkS")
		)
		(fp_line
			(start 1.03378 0.4826)
			(end -0.79248 0.4826)
			(stroke
				(width 0.1524)
				(type default)
			)
			(layer "F.SilkS")
		)
		(fp_line
			(start 1.03378 -0.4826)
			(end 1.03378 0.4826)
			(stroke
				(width 0.1524)
				(type default)
			)
			(layer "F.SilkS")
		)
		(fp_line
			(start 0.90678 0.4826)
			(end -0.90678 0.4826)
			(stroke
				(width 0.1524)
				(type default)
			)
			(layer "F.SilkS")
		)
		(fp_line
			(start 0.90678 -0.4826)
			(end 0.90678 0.4826)
			(stroke
				(width 0.1524)
				(type default)
			)
			(layer "F.SilkS")
		)
		(fp_line
			(start -0.64008 -0.4826)
			(end 1.16078 -0.4826)
			(stroke
				(width 0.1524)
				(type default)
			)
			(layer "F.SilkS")
		)
		(fp_line
			(start -0.79248 -0.4826)
			(end 1.03378 -0.4826)
			(stroke
				(width 0.1524)
				(type default)
			)
			(layer "F.SilkS")
		)
		(fp_line
			(start -0.89408 -0.4826)
			(end 0.90678 -0.4826)
			(stroke
				(width 0.1524)
				(type default)
			)
			(layer "F.SilkS")
		)
		(fp_line
			(start -0.90678 0.4826)
			(end -0.90678 -0.4699)
			(stroke
				(width 0.1524)
				(type default)
			)
			(layer "F.SilkS")
		)
		(fp_line
			(start 0.499872 0.249936)
			(end -0.499872 0.249936)
			(stroke
				(width 0.1)
				(type default)
			)
			(layer "F.Fab")
		)
		(fp_line
			(start 0.499872 -0.249936)
			(end 0.499872 0.249936)
			(stroke
				(width 0.1)
				(type default)
			)
			(layer "F.Fab")
		)
		(fp_line
			(start -0.499872 0.249936)
			(end -0.499872 -0.249936)
			(stroke
				(width 0.1)
				(type default)
			)
			(layer "F.Fab")
		)
		(fp_line
			(start -0.499872 -0.249936)
			(end 0.499872 -0.249936)
			(stroke
				(width 0.1)
				(type default)
			)
			(layer "F.Fab")
		)
		(pad "A" smd rect
			(at -0.47498 0 180)
			(size 0.6096 0.7112)
			(layers "F.Cu" "F.Mask" "F.Paste")
			(net "LED_PEX0_SYS_ERR_N")
		)
		(pad "C" smd rect
			(at 0.47498 0 180)
			(size 0.6096 0.7112)
			(layers "F.Cu" "F.Mask" "F.Paste")
			(net "PEX0_SYS_ERR_3V3_N")
		)
	)
	(footprint ""
		(layer "F.Cu")
		(at 222.130874 -50.52695 -90)
		(property "Reference" "R1753"
			(at 0 0 270)
			(layer "F.SilkS")
			(hide yes)
			(effects
				(font
					(size 1.27 1.27)
				)
			)
		)
		(property "Value" ""
			(at 0 0 270)
			(layer "F.Fab")
			(effects
				(font
					(size 1.27 1.27)
				)
			)
		)
		(duplicate_pad_numbers_are_jumpers no)
		(fp_line
			(start -0.7874 0.4064)
			(end -0.7874 -0.4064)
			(stroke
				(width 0.1524)
				(type default)
			)
			(layer "F.SilkS")
		)
		(fp_line
			(start 0.7874 0.4064)
			(end -0.7874 0.4064)
			(stroke
				(width 0.1524)
				(type default)
			)
			(layer "F.SilkS")
		)
		(fp_line
			(start -0.7874 -0.4064)
			(end 0.7874 -0.4064)
			(stroke
				(width 0.1524)
				(type default)
			)
			(layer "F.SilkS")
		)
		(fp_line
			(start 0.7874 -0.4064)
			(end 0.7874 0.4064)
			(stroke
				(width 0.1524)
				(type default)
			)
			(layer "F.SilkS")
		)
		(fp_line
			(start -0.67945 0.3048)
			(end -0.67945 -0.305054)
			(stroke
				(width 0.1)
				(type default)
			)
			(layer "F.Fab")
		)
		(fp_line
			(start -0.12065 0.3048)
			(end -0.67945 0.3048)
			(stroke
				(width 0.1)
				(type default)
			)
			(layer "F.Fab")
		)
		(fp_line
			(start 0.120396 0.3048)
			(end 0.120396 0.2794)
			(stroke
				(width 0.1)
				(type default)
			)
			(layer "F.Fab")
		)
		(fp_line
			(start 0.67945 0.3048)
			(end 0.120396 0.3048)
			(stroke
				(width 0.1)
				(type default)
			)
			(layer "F.Fab")
		)
		(fp_line
			(start -0.12065 0.2794)
			(end -0.12065 0.3048)
			(stroke
				(width 0.1)
				(type default)
			)
			(layer "F.Fab")
		)
		(fp_line
			(start 0.120396 0.2794)
			(end -0.12065 0.2794)
			(stroke
				(width 0.1)
				(type default)
			)
			(layer "F.Fab")
		)
		(fp_line
			(start -0.12065 -0.2794)
			(end 0.12065 -0.2794)
			(stroke
				(width 0.1)
				(type default)
			)
			(layer "F.Fab")
		)
		(fp_line
			(start 0.12065 -0.2794)
			(end 0.12065 -0.3048)
			(stroke
				(width 0.1)
				(type default)
			)
			(layer "F.Fab")
		)
		(fp_line
			(start 0.12065 -0.3048)
			(end 0.67945 -0.3048)
			(stroke
				(width 0.1)
				(type default)
			)
			(layer "F.Fab")
		)
		(fp_line
			(start 0.67945 -0.3048)
			(end 0.67945 0.3048)
			(stroke
				(width 0.1)
				(type default)
			)
			(layer "F.Fab")
		)
		(fp_line
			(start -0.67945 -0.305054)
			(end -0.12065 -0.305054)
			(stroke
				(width 0.1)
				(type default)
			)
			(layer "F.Fab")
		)
		(fp_line
			(start -0.12065 -0.305054)
			(end -0.12065 -0.2794)
			(stroke
				(width 0.1)
				(type default)
			)
			(layer "F.Fab")
		)
		(pad "1" smd circle
			(at -0.40005 0 270)
			(size 0 0)
			(layers "F.Cu" "F.Mask" "F.Paste")
			(net "P3V3_AUX")
		)
		(pad "2" smd circle
			(at 0.40005 0 270)
			(size 0 0)
			(layers "F.Cu" "F.Mask" "F.Paste")
			(net "SMB_BIC_I2C6_MUX_SSD_0_7_ADC_R_SCL")
		)
	)
)
